(kicad_pcb
	(version 20260206)
	(generator "pcbnew")
	(generator_version "10.0")
	(general
		(thickness 1.6)
		(legacy_teardrops no)
	)
	(paper "A4")
	(title_block
		(title "03242023_DA0F0TMBIJ0_F0T_Motherboard_J_brd_V01_OCP.brd")
		(comment 1 "Grand Teton / footprints 4422-4426 of 6105")
	)
	(layers
		(0 "F.Cu" signal "TOP")
		(4 "In1.Cu" signal "GND")
		(6 "In2.Cu" signal "IN1")
		(8 "In3.Cu" signal "GND1")
		(10 "In4.Cu" signal "IN2")
		(12 "In5.Cu" signal "GND2")
		(14 "In6.Cu" signal "IN3")
		(16 "In7.Cu" signal "GND3")
		(18 "In8.Cu" signal "VCC")
		(20 "In9.Cu" signal "VCC1")
		(22 "In10.Cu" signal "GND4")
		(24 "In11.Cu" signal "IN4")
		(26 "In12.Cu" signal "GND5")
		(28 "In13.Cu" signal "IN5")
		(30 "In14.Cu" signal "GND6")
		(32 "In15.Cu" signal "IN6")
		(34 "In16.Cu" signal "GND7")
		(2 "B.Cu" signal "BOTTOM")
		(9 "F.Adhes" user "F.Adhesive")
		(11 "B.Adhes" user "B.Adhesive")
		(13 "F.Paste" user "Package Geometry/Pastemask Top")
		(15 "B.Paste" user "Package Geometry/Pastemask Bottom")
		(5 "F.SilkS" user "Ref Des/Silkscreen Top")
		(7 "B.SilkS" user "Ref Des/Silkscreen Bottom")
		(1 "F.Mask" user "Board Geometry/Soldermask Top")
		(3 "B.Mask" user "Board Geometry/Soldermask Bottom")
		(17 "Dwgs.User" user "User.Drawings")
		(19 "Cmts.User" user "User.Comments")
		(21 "Eco1.User" user "User.Eco1")
		(23 "Eco2.User" user "User.Eco2")
		(25 "Edge.Cuts" user "Board Geometry/Outline")
		(27 "Margin" user)
		(31 "F.CrtYd" user "Package Geometry/Place Bound Top")
		(29 "B.CrtYd" user "Package Geometry/Place Bound Bottom")
		(35 "F.Fab" user "Ref Des/Assembly Top")
		(33 "B.Fab" user "Ref Des/Assembly Bottom")
	)
	(footprint ""
		(layer "B.Cu")
		(at 127.84074 -26.276808 -90)
		(property "Reference" "U309"
			(at 0 0 90)
			(layer "B.SilkS")
			(hide yes)
			(effects
				(font
					(size 1.27 1.27)
				)
				(justify mirror)
			)
		)
		(property "Value" ""
			(at 0 0 90)
			(layer "B.Fab")
			(effects
				(font
					(size 1.27 1.27)
				)
				(justify mirror)
			)
		)
		(duplicate_pad_numbers_are_jumpers no)
		(fp_line
			(start -1.618742 1.618742)
			(end -1.17856 1.618742)
			(stroke
				(width 0.1524)
				(type default)
			)
			(layer "B.SilkS")
		)
		(fp_line
			(start -0.42418 1.618742)
			(end 0.37592 1.618742)
			(stroke
				(width 0.1524)
				(type default)
			)
			(layer "B.SilkS")
		)
		(fp_line
			(start 1.32588 1.618742)
			(end 1.618742 1.618742)
			(stroke
				(width 0.1524)
				(type default)
			)
			(layer "B.SilkS")
		)
		(fp_line
			(start 1.618742 1.618742)
			(end 1.618742 -1.618742)
			(stroke
				(width 0.1524)
				(type default)
			)
			(layer "B.SilkS")
		)
		(fp_line
			(start -1.618742 -1.618742)
			(end -1.618742 1.618742)
			(stroke
				(width 0.1524)
				(type default)
			)
			(layer "B.SilkS")
		)
		(fp_line
			(start -1.27 -1.618742)
			(end -1.618742 -1.618742)
			(stroke
				(width 0.1524)
				(type default)
			)
			(layer "B.SilkS")
		)
		(fp_line
			(start 0.42164 -1.618742)
			(end -0.29464 -1.618742)
			(stroke
				(width 0.1524)
				(type default)
			)
			(layer "B.SilkS")
		)
		(fp_line
			(start 1.618742 -1.618742)
			(end 1.52146 -1.618742)
			(stroke
				(width 0.1524)
				(type default)
			)
			(layer "B.SilkS")
		)
		(fp_poly
			(pts
				(xy 2.663952 -1.172972) (xy 1.855724 -0.903478) (xy 2.124964 -1.711706)
			)
			(stroke
				(width 0)
				(type default)
			)
			(fill yes)
			(layer "B.SilkS")
		)
		(fp_line
			(start -1.27508 1.27508)
			(end -1.27508 -1.27508)
			(stroke
				(width 0.1)
				(type default)
			)
			(layer "B.Fab")
		)
		(fp_line
			(start 1.27508 1.27508)
			(end -1.27508 1.27508)
			(stroke
				(width 0.1)
				(type default)
			)
			(layer "B.Fab")
		)
		(fp_line
			(start -1.27508 -1.27508)
			(end 1.27508 -1.27508)
			(stroke
				(width 0.1)
				(type default)
			)
			(layer "B.Fab")
		)
		(fp_line
			(start 1.27508 -1.27508)
			(end 1.27508 1.27508)
			(stroke
				(width 0.1)
				(type default)
			)
			(layer "B.Fab")
		)
		(fp_poly
			(pts
				(xy 2.4892 -1.081024) (xy 2.4892 -0.319024) (xy 1.7272 -0.700024)
			)
			(stroke
				(width 0)
				(type default)
			)
			(fill yes)
			(layer "B.Fab")
		)
		(pad "1" smd rect
			(at 1.225042 -0.700024)
			(size 0.127 0.508)
			(layers "B.Cu" "B.Mask" "B.Paste")
			(net "FM_USB3_1_EQA")
		)
		(pad "2" smd rect
			(at 1.225042 -0.350012)
			(size 0.127 0.508)
			(layers "B.Cu" "B.Mask" "B.Paste")
			(net "FM_USB3_1_FGA")
		)
		(pad "3" smd rect
			(at 1.225042 0)
			(size 0.127 0.508)
			(layers "B.Cu" "B.Mask" "B.Paste")
			(net "FM_USB3_1_SWA")
		)
		(pad "4" smd rect
			(at 1.225042 0.350012)
			(size 0.127 0.508)
			(layers "B.Cu" "B.Mask" "B.Paste")
			(net "FM_USB3_1_EN_N")
		)
		(pad "5" smd rect
			(at 1.225042 0.700024)
			(size 0.127 0.508)
			(layers "B.Cu" "B.Mask" "B.Paste")
			(net "P3V3_AUX_USB_BUF")
		)
		(pad "6" smd rect
			(at 1.050036 1.225042 90)
			(size 0.127 0.508)
			(layers "B.Cu" "B.Mask" "B.Paste")
			(net "USB3_PCH_TX_C_DP<4>")
		)
		(pad "7" smd rect
			(at 0.700024 1.225042 90)
			(size 0.127 0.508)
			(layers "B.Cu" "B.Mask" "B.Paste")
			(net "USB3_PCH_TX_C_DN<4>")
		)
		(pad "8" smd rect
			(at 0.350012 1.225042 90)
			(size 0.127 0.508)
			(layers "B.Cu" "B.Mask" "B.Paste")
			(net "GND")
		)
		(pad "9" smd rect
			(at 0 1.225042 90)
			(size 0.127 0.508)
			(layers "B.Cu" "B.Mask" "B.Paste")
			(net "GND")
		)
		(pad "10" smd rect
			(at -0.350012 1.225042 90)
			(size 0.127 0.508)
			(layers "B.Cu" "B.Mask" "B.Paste")
			(net "GND")
		)
		(pad "11" smd rect
			(at -0.700024 1.225042 90)
			(size 0.127 0.508)
			(layers "B.Cu" "B.Mask" "B.Paste")
			(net "USB3_PCH_RX_BUF_C_DN<4>")
		)
		(pad "12" smd rect
			(at -1.050036 1.225042 90)
			(size 0.127 0.508)
			(layers "B.Cu" "B.Mask" "B.Paste")
			(net "USB3_PCH_RX_BUF_C_DP<4>")
		)
		(pad "13" smd rect
			(at -1.225042 0.700024)
			(size 0.127 0.508)
			(layers "B.Cu" "B.Mask" "B.Paste")
			(net "FM_USB3_1_RXDET_EN")
		)
		(pad "14" smd rect
			(at -1.225042 0.350012)
			(size 0.127 0.508)
			(layers "B.Cu" "B.Mask" "B.Paste")
			(net "FM_USB3_1_SWB")
		)
		(pad "15" smd rect
			(at -1.225042 0)
			(size 0.127 0.508)
			(layers "B.Cu" "B.Mask" "B.Paste")
			(net "FM_USB3_1_FGB")
		)
		(pad "16" smd rect
			(at -1.225042 -0.350012)
			(size 0.127 0.508)
			(layers "B.Cu" "B.Mask" "B.Paste")
			(net "FM_USB3_1_EQB")
		)
		(pad "17" smd rect
			(at -1.225042 -0.700024)
			(size 0.127 0.508)
			(layers "B.Cu" "B.Mask" "B.Paste")
			(net "P3V3_AUX_USB_BUF")
		)
		(pad "18" smd rect
			(at -1.050036 -1.225042 90)
			(size 0.127 0.508)
			(layers "B.Cu" "B.Mask" "B.Paste")
			(net "USB3_PCH_RX_C_DP<4>")
		)
		(pad "19" smd rect
			(at -0.700024 -1.225042 90)
			(size 0.127 0.508)
			(layers "B.Cu" "B.Mask" "B.Paste")
			(net "USB3_PCH_RX_C_DN<4>")
		)
		(pad "20" smd rect
			(at -0.350012 -1.225042 90)
			(size 0.127 0.508)
			(layers "B.Cu" "B.Mask" "B.Paste")
			(net "GND")
		)
		(pad "21" smd rect
			(at 0 -1.225042 90)
			(size 0.127 0.508)
			(layers "B.Cu" "B.Mask" "B.Paste")
			(net "GND")
		)
		(pad "22" smd rect
			(at 0.350012 -1.225042 90)
			(size 0.127 0.508)
			(layers "B.Cu" "B.Mask" "B.Paste")
			(net "GND")
		)
		(pad "23" smd rect
			(at 0.700024 -1.225042 90)
			(size 0.127 0.508)
			(layers "B.Cu" "B.Mask" "B.Paste")
			(net "USB3_PCH_TX_BUF_DN<4>")
		)
		(pad "24" smd rect
			(at 1.050036 -1.225042 90)
			(size 0.127 0.508)
			(layers "B.Cu" "B.Mask" "B.Paste")
			(net "USB3_PCH_TX_BUF_DP<4>")
		)
		(pad "TH" smd rect
			(at 0 0 90)
			(size 1.4224 1.4224)
			(layers "B.Cu" "B.Mask" "B.Paste")
			(net "GND")
		)
	)
	(footprint ""
		(layer "B.Cu")
		(at 330.16698 -64.260984 45)
		(property "Reference" "C1254"
			(at 0 0 45)
			(layer "B.SilkS")
			(hide yes)
			(effects
				(font
					(size 1.27 1.27)
				)
				(justify mirror)
			)
		)
		(property "Value" ""
			(at 0 0 45)
			(layer "B.Fab")
			(effects
				(font
					(size 1.27 1.27)
				)
				(justify mirror)
			)
		)
		(duplicate_pad_numbers_are_jumpers no)
		(fp_line
			(start -1.295492 -0.584255)
			(end -1.295492 0.584255)
			(stroke
				(width 0.1524)
				(type default)
			)
			(layer "B.SilkS")
		)
		(fp_line
			(start -1.295492 0.584255)
			(end 1.295492 0.584255)
			(stroke
				(width 0.1524)
				(type default)
			)
			(layer "B.SilkS")
		)
		(fp_line
			(start 0 -0.584076)
			(end 0 0.584076)
			(stroke
				(width 0.1524)
				(type default)
			)
			(layer "B.SilkS")
		)
		(fp_line
			(start 1.295492 -0.584255)
			(end -1.295492 -0.584255)
			(stroke
				(width 0.1524)
				(type default)
			)
			(layer "B.SilkS")
		)
		(fp_line
			(start 1.295492 0.584255)
			(end 1.295492 -0.584255)
			(stroke
				(width 0.1524)
				(type default)
			)
			(layer "B.SilkS")
		)
		(fp_line
			(start -1.193835 -0.406446)
			(end -1.193835 0.406446)
			(stroke
				(width 0.1)
				(type default)
			)
			(layer "B.Fab")
		)
		(fp_line
			(start -0.863541 -0.457275)
			(end -0.863721 -0.406446)
			(stroke
				(width 0.1)
				(type default)
			)
			(layer "B.Fab")
		)
		(fp_line
			(start -0.863721 -0.406446)
			(end -1.193835 -0.406446)
			(stroke
				(width 0.1)
				(type default)
			)
			(layer "B.Fab")
		)
		(fp_line
			(start -1.193835 0.406446)
			(end -0.863721 0.406446)
			(stroke
				(width 0.1)
				(type default)
			)
			(layer "B.Fab")
		)
		(fp_line
			(start -0.863721 0.406446)
			(end -0.863541 0.457275)
			(stroke
				(width 0.1)
				(type default)
			)
			(layer "B.Fab")
		)
		(fp_line
			(start -0.863541 0.457275)
			(end 0.863541 0.457275)
			(stroke
				(width 0.1)
				(type default)
			)
			(layer "B.Fab")
		)
		(fp_line
			(start 0.863541 -0.457275)
			(end -0.863541 -0.457275)
			(stroke
				(width 0.1)
				(type default)
			)
			(layer "B.Fab")
		)
		(fp_line
			(start 0.863721 -0.406446)
			(end 0.863541 -0.457275)
			(stroke
				(width 0.1)
				(type default)
			)
			(layer "B.Fab")
		)
		(fp_line
			(start 1.193835 -0.406446)
			(end 0.863721 -0.406446)
			(stroke
				(width 0.1)
				(type default)
			)
			(layer "B.Fab")
		)
		(fp_line
			(start 0.863721 0.406446)
			(end 1.193835 0.406446)
			(stroke
				(width 0.1)
				(type default)
			)
			(layer "B.Fab")
		)
		(fp_line
			(start 0.863541 0.457275)
			(end 0.863721 0.406446)
			(stroke
				(width 0.1)
				(type default)
			)
			(layer "B.Fab")
		)
		(fp_line
			(start 1.193835 0.406446)
			(end 1.193835 -0.406446)
			(stroke
				(width 0.1)
				(type default)
			)
			(layer "B.Fab")
		)
		(pad "1" smd rect
			(at 0.7366 0 315)
			(size 0.7112 0.8128)
			(layers "B.Cu" "B.Mask" "B.Paste")
			(net "P1V05_PCH_PLL_AUX")
		)
		(pad "2" smd rect
			(at -0.7366 0 315)
			(size 0.7112 0.8128)
			(layers "B.Cu" "B.Mask" "B.Paste")
			(net "GND")
		)
	)
	(footprint ""
		(layer "B.Cu")
		(at 235.811822 -132.103114 90)
		(property "Reference" "R107"
			(at 0 0 90)
			(layer "B.SilkS")
			(hide yes)
			(effects
				(font
					(size 1.27 1.27)
				)
				(justify mirror)
			)
		)
		(property "Value" ""
			(at 0 0 90)
			(layer "B.Fab")
			(effects
				(font
					(size 1.27 1.27)
				)
				(justify mirror)
			)
		)
		(duplicate_pad_numbers_are_jumpers no)
		(fp_line
			(start 0.7874 -0.4064)
			(end -0.7874 -0.4064)
			(stroke
				(width 0.1524)
				(type default)
			)
			(layer "B.SilkS")
		)
		(fp_line
			(start -0.7874 -0.4064)
			(end -0.7874 0.4064)
			(stroke
				(width 0.1524)
				(type default)
			)
			(layer "B.SilkS")
		)
		(fp_line
			(start 0.7874 0.4064)
			(end 0.7874 -0.4064)
			(stroke
				(width 0.1524)
				(type default)
			)
			(layer "B.SilkS")
		)
		(fp_line
			(start -0.7874 0.4064)
			(end 0.7874 0.4064)
			(stroke
				(width 0.1524)
				(type default)
			)
			(layer "B.SilkS")
		)
		(fp_line
			(start 0.67945 -0.305054)
			(end 0.12065 -0.305054)
			(stroke
				(width 0.1)
				(type default)
			)
			(layer "B.Fab")
		)
		(fp_line
			(start 0.12065 -0.305054)
			(end 0.12065 -0.2794)
			(stroke
				(width 0.1)
				(type default)
			)
			(layer "B.Fab")
		)
		(fp_line
			(start -0.12065 -0.3048)
			(end -0.67945 -0.3048)
			(stroke
				(width 0.1)
				(type default)
			)
			(layer "B.Fab")
		)
		(fp_line
			(start -0.67945 -0.3048)
			(end -0.67945 0.3048)
			(stroke
				(width 0.1)
				(type default)
			)
			(layer "B.Fab")
		)
		(fp_line
			(start 0.12065 -0.2794)
			(end -0.12065 -0.2794)
			(stroke
				(width 0.1)
				(type default)
			)
			(layer "B.Fab")
		)
		(fp_line
			(start -0.12065 -0.2794)
			(end -0.12065 -0.3048)
			(stroke
				(width 0.1)
				(type default)
			)
			(layer "B.Fab")
		)
		(fp_line
			(start 0.12065 0.2794)
			(end 0.12065 0.3048)
			(stroke
				(width 0.1)
				(type default)
			)
			(layer "B.Fab")
		)
		(fp_line
			(start -0.120396 0.2794)
			(end 0.12065 0.2794)
			(stroke
				(width 0.1)
				(type default)
			)
			(layer "B.Fab")
		)
		(fp_line
			(start 0.67945 0.3048)
			(end 0.67945 -0.305054)
			(stroke
				(width 0.1)
				(type default)
			)
			(layer "B.Fab")
		)
		(fp_line
			(start 0.12065 0.3048)
			(end 0.67945 0.3048)
			(stroke
				(width 0.1)
				(type default)
			)
			(layer "B.Fab")
		)
		(fp_line
			(start -0.120396 0.3048)
			(end -0.120396 0.2794)
			(stroke
				(width 0.1)
				(type default)
			)
			(layer "B.Fab")
		)
		(fp_line
			(start -0.67945 0.3048)
			(end -0.120396 0.3048)
			(stroke
				(width 0.1)
				(type default)
			)
			(layer "B.Fab")
		)
		(pad "1" smd circle
			(at 0.40005 0 270)
			(size 0 0)
			(layers "B.Cu" "B.Mask" "B.Paste")
			(net "SMB_HOST_3V3AUX_SCL_R")
		)
		(pad "2" smd circle
			(at -0.40005 0 270)
			(size 0 0)
			(layers "B.Cu" "B.Mask" "B.Paste")
			(net "SMB_HOST_CLK_BUF_3V3AUX_SCL")
		)
	)
	(footprint ""
		(layer "B.Cu")
		(at 450.43725 -45.288962)
		(property "Reference" "R424"
			(at 0 0 0)
			(layer "B.SilkS")
			(hide yes)
			(effects
				(font
					(size 1.27 1.27)
				)
				(justify mirror)
			)
		)
		(property "Value" ""
			(at 0 0 0)
			(layer "B.Fab")
			(effects
				(font
					(size 1.27 1.27)
				)
				(justify mirror)
			)
		)
		(duplicate_pad_numbers_are_jumpers no)
		(fp_line
			(start -0.7874 -0.4064)
			(end -0.7874 0.4064)
			(stroke
				(width 0.1524)
				(type default)
			)
			(layer "B.SilkS")
		)
		(fp_line
			(start -0.7874 0.4064)
			(end 0.7874 0.4064)
			(stroke
				(width 0.1524)
				(type default)
			)
			(layer "B.SilkS")
		)
		(fp_line
			(start 0.7874 -0.4064)
			(end -0.7874 -0.4064)
			(stroke
				(width 0.1524)
				(type default)
			)
			(layer "B.SilkS")
		)
		(fp_line
			(start 0.7874 0.4064)
			(end 0.7874 -0.4064)
			(stroke
				(width 0.1524)
				(type default)
			)
			(layer "B.SilkS")
		)
		(fp_line
			(start -0.67945 -0.3048)
			(end -0.67945 0.3048)
			(stroke
				(width 0.1)
				(type default)
			)
			(layer "B.Fab")
		)
		(fp_line
			(start -0.67945 0.3048)
			(end -0.120396 0.3048)
			(stroke
				(width 0.1)
				(type default)
			)
			(layer "B.Fab")
		)
		(fp_line
			(start -0.12065 -0.3048)
			(end -0.67945 -0.3048)
			(stroke
				(width 0.1)
				(type default)
			)
			(layer "B.Fab")
		)
		(fp_line
			(start -0.12065 -0.2794)
			(end -0.12065 -0.3048)
			(stroke
				(width 0.1)
				(type default)
			)
			(layer "B.Fab")
		)
		(fp_line
			(start -0.120396 0.2794)
			(end 0.12065 0.2794)
			(stroke
				(width 0.1)
				(type default)
			)
			(layer "B.Fab")
		)
		(fp_line
			(start -0.120396 0.3048)
			(end -0.120396 0.2794)
			(stroke
				(width 0.1)
				(type default)
			)
			(layer "B.Fab")
		)
		(fp_line
			(start 0.12065 -0.305054)
			(end 0.12065 -0.2794)
			(stroke
				(width 0.1)
				(type default)
			)
			(layer "B.Fab")
		)
		(fp_line
			(start 0.12065 -0.2794)
			(end -0.12065 -0.2794)
			(stroke
				(width 0.1)
				(type default)
			)
			(layer "B.Fab")
		)
		(fp_line
			(start 0.12065 0.2794)
			(end 0.12065 0.3048)
			(stroke
				(width 0.1)
				(type default)
			)
			(layer "B.Fab")
		)
		(fp_line
			(start 0.12065 0.3048)
			(end 0.67945 0.3048)
			(stroke
				(width 0.1)
				(type default)
			)
			(layer "B.Fab")
		)
		(fp_line
			(start 0.67945 -0.305054)
			(end 0.12065 -0.305054)
			(stroke
				(width 0.1)
				(type default)
			)
			(layer "B.Fab")
		)
		(fp_line
			(start 0.67945 0.3048)
			(end 0.67945 -0.305054)
			(stroke
				(width 0.1)
				(type default)
			)
			(layer "B.Fab")
		)
		(pad "1" smd circle
			(at 0.40005 0 180)
			(size 0 0)
			(layers "B.Cu" "B.Mask" "B.Paste")
			(net "SMB_OCP_SFF_3V3AUX_BUF_R_SCL")
		)
		(pad "2" smd circle
			(at -0.40005 0 180)
			(size 0 0)
			(layers "B.Cu" "B.Mask" "B.Paste")
			(net "SMB_OCP_SFF_3V3AUX_BUF_SCL")
		)
	)
	(footprint ""
		(layer "B.Cu")
		(at 195.246498 -191.307466 180)
		(property "Reference" "R745"
			(at 0 0 0)
			(layer "B.SilkS")
			(hide yes)
			(effects
				(font
					(size 1.27 1.27)
				)
				(justify mirror)
			)
		)
		(property "Value" ""
			(at 0 0 0)
			(layer "B.Fab")
			(effects
				(font
					(size 1.27 1.27)
				)
				(justify mirror)
			)
		)
		(duplicate_pad_numbers_are_jumpers no)
		(fp_line
			(start 0.7874 0.4064)
			(end 0.7874 -0.4064)
			(stroke
				(width 0.1524)
				(type default)
			)
			(layer "B.SilkS")
		)
		(fp_line
			(start 0.7874 -0.4064)
			(end -0.7874 -0.4064)
			(stroke
				(width 0.1524)
				(type default)
			)
			(layer "B.SilkS")
		)
		(fp_line
			(start -0.7874 0.4064)
			(end 0.7874 0.4064)
			(stroke
				(width 0.1524)
				(type default)
			)
			(layer "B.SilkS")
		)
		(fp_line
			(start -0.7874 -0.4064)
			(end -0.7874 0.4064)
			(stroke
				(width 0.1524)
				(type default)
			)
			(layer "B.SilkS")
		)
		(fp_line
			(start 0.67945 0.3048)
			(end 0.67945 -0.305054)
			(stroke
				(width 0.1)
				(type default)
			)
			(layer "B.Fab")
		)
		(fp_line
			(start 0.67945 -0.305054)
			(end 0.12065 -0.305054)
			(stroke
				(width 0.1)
				(type default)
			)
			(layer "B.Fab")
		)
		(fp_line
			(start 0.12065 0.3048)
			(end 0.67945 0.3048)
			(stroke
				(width 0.1)
				(type default)
			)
			(layer "B.Fab")
		)
		(fp_line
			(start 0.12065 0.2794)
			(end 0.12065 0.3048)
			(stroke
				(width 0.1)
				(type default)
			)
			(layer "B.Fab")
		)
		(fp_line
			(start 0.12065 -0.2794)
			(end -0.12065 -0.2794)
			(stroke
				(width 0.1)
				(type default)
			)
			(layer "B.Fab")
		)
		(fp_line
			(start 0.12065 -0.305054)
			(end 0.12065 -0.2794)
			(stroke
				(width 0.1)
				(type default)
			)
			(layer "B.Fab")
		)
		(fp_line
			(start -0.120396 0.3048)
			(end -0.120396 0.2794)
			(stroke
				(width 0.1)
				(type default)
			)
			(layer "B.Fab")
		)
		(fp_line
			(start -0.120396 0.2794)
			(end 0.12065 0.2794)
			(stroke
				(width 0.1)
				(type default)
			)
			(layer "B.Fab")
		)
		(fp_line
			(start -0.12065 -0.2794)
			(end -0.12065 -0.3048)
			(stroke
				(width 0.1)
				(type default)
			)
			(layer "B.Fab")
		)
		(fp_line
			(start -0.12065 -0.3048)
			(end -0.67945 -0.3048)
			(stroke
				(width 0.1)
				(type default)
			)
			(layer "B.Fab")
		)
		(fp_line
			(start -0.67945 0.3048)
			(end -0.120396 0.3048)
			(stroke
				(width 0.1)
				(type default)
			)
			(layer "B.Fab")
		)
		(fp_line
			(start -0.67945 -0.3048)
			(end -0.67945 0.3048)
			(stroke
				(width 0.1)
				(type default)
			)
			(layer "B.Fab")
		)
		(pad "1" smd circle
			(at 0.40005 0)
			(size 0 0)
			(layers "B.Cu" "B.Mask" "B.Paste")
			(net "FM_CPU_EN")
		)
		(pad "2" smd circle
			(at -0.40005 0)
			(size 0 0)
			(layers "B.Cu" "B.Mask" "B.Paste")
			(net "FM_CPU_EN_R")
		)
	)
)
